(kicad_pcb
	(version 20241229)
	(generator "pcbnew")
	(generator_version "9.0")
	(general
		(thickness 1.258)
		(legacy_teardrops no)
	)
	(paper "A4")
	(title_block
		(date "2024-05-27")
		(rev "1.1.2")
		(comment 9 "footprints 43-48 of 64")
	)
	(layers
		(0 "F.Cu" signal)
		(4 "In1.Cu" power)
		(6 "In2.Cu" power)
		(8 "In3.Cu" signal)
		(10 "In4.Cu" signal)
		(2 "B.Cu" signal)
		(9 "F.Adhes" user "F.Adhesive")
		(11 "B.Adhes" user "B.Adhesive")
		(13 "F.Paste" user)
		(15 "B.Paste" user)
		(5 "F.SilkS" user "F.Silkscreen")
		(7 "B.SilkS" user "B.Silkscreen")
		(1 "F.Mask" user)
		(3 "B.Mask" user)
		(17 "Dwgs.User" user "User.Drawings")
		(19 "Cmts.User" user "User.Comments")
		(21 "Eco1.User" user "User.Eco1")
		(23 "Eco2.User" user "User.Eco2")
		(25 "Edge.Cuts" user)
		(27 "Margin" user)
		(31 "F.CrtYd" user "F.Courtyard")
		(29 "B.CrtYd" user "B.Courtyard")
		(35 "F.Fab" user)
		(33 "B.Fab" user)
	)
	(footprint "antmicro-footprints:C_0201"
		(layer "B.Cu")
		(at 156.5 88.85)
		(descr "Capacitor SMD 0201")
		(tags "capacitor SMD 0201")
		(property "Reference" "C3"
			(at 2.86 0.37 180)
			(layer "B.SilkS")
			(effects
				(font
					(size 0.7 0.7)
					(thickness 0.15)
				)
				(justify left bottom mirror)
			)
		)
		(property "Value" "C_100n_0201"
			(at 0 -1.4 180)
			(layer "B.Fab")
			(hide yes)
			(effects
				(font
					(size 0.7 0.7)
					(thickness 0.15)
				)
				(justify left bottom mirror)
			)
		)
		(property "Description" "SMD Multilayer Ceramic Capacitor, 0.1 µF, 6.3 V, 0201 [0603 Metric], ± 10%, X6S, CC Series"
			(at 0 0 0)
			(layer "F.Fab")
			(hide yes)
			(effects
				(font
					(size 1.27 1.27)
					(thickness 0.15)
				)
			)
		)
		(property "Author" "Antmicro"
			(at 0 0 0)
			(layer "B.Fab")
			(hide yes)
			(effects
				(font
					(size 1 1)
					(thickness 0.15)
				)
				(justify mirror)
			)
		)
		(property "Dielectric" ""
			(at 0 0 0)
			(layer "B.Fab")
			(hide yes)
			(effects
				(font
					(size 1 1)
					(thickness 0.15)
				)
				(justify mirror)
			)
		)
		(property "License" "Apache-2.0"
			(at 0 0 0)
			(layer "B.Fab")
			(hide yes)
			(effects
				(font
					(size 1 1)
					(thickness 0.15)
				)
				(justify mirror)
			)
		)
		(property "MPN" "CC0201KRX6S5BB104"
			(at 0 0 0)
			(layer "B.Fab")
			(hide yes)
			(effects
				(font
					(size 1 1)
					(thickness 0.15)
				)
				(justify mirror)
			)
		)
		(property "Manufacturer" "YAGEO"
			(at 0 0 0)
			(layer "B.Fab")
			(hide yes)
			(effects
				(font
					(size 1 1)
					(thickness 0.15)
				)
				(justify mirror)
			)
		)
		(property "Public" "False"
			(at 0 0 0)
			(layer "B.Fab")
			(hide yes)
			(effects
				(font
					(size 1 1)
					(thickness 0.15)
				)
				(justify mirror)
			)
		)
		(property "Val" "100n"
			(at 0 0 0)
			(layer "B.Fab")
			(hide yes)
			(effects
				(font
					(size 1 1)
					(thickness 0.15)
				)
				(justify mirror)
			)
		)
		(property "Voltage" ""
			(at 0 0 0)
			(layer "B.Fab")
			(hide yes)
			(effects
				(font
					(size 1 1)
					(thickness 0.15)
				)
				(justify mirror)
			)
		)
		(sheetname "DDR5")
		(sheetfile "ddr5.kicad_sch")
		(attr smd)
		(fp_rect
			(start -0.7 0.35)
			(end 0.7 -0.35)
			(stroke
				(width 0.05)
				(type default)
			)
			(fill no)
			(layer "B.CrtYd")
		)
		(fp_rect
			(start 0.3 -0.15)
			(end -0.301 0.149)
			(stroke
				(width 0.15)
				(type solid)
			)
			(fill no)
			(layer "B.Fab")
		)
		(pad "" smd roundrect
			(at -0.349 0.002)
			(size 0.318 0.36)
			(layers "B.Paste")
			(roundrect_rratio 0.25)
		)
		(pad "" smd roundrect
			(at 0.341 0.002)
			(size 0.318 0.36)
			(layers "B.Paste")
			(roundrect_rratio 0.25)
		)
		(pad "1" smd roundrect
			(at -0.321 0.002)
			(size 0.46 0.4)
			(layers "B.Cu" "B.Mask")
			(roundrect_rratio 0.25)
			(net 18 "VDD")
			(pintype "passive")
		)
		(pad "2" smd roundrect
			(at 0.32 0.002)
			(size 0.46 0.4)
			(layers "B.Cu" "B.Mask")
			(roundrect_rratio 0.25)
			(net 1 "GND")
			(pintype "passive")
		)
	)
	(footprint "antmicro-footprints:C_0201"
		(layer "B.Cu")
		(at 153.3 82.45)
		(descr "Capacitor SMD 0201")
		(tags "capacitor SMD 0201")
		(property "Reference" "C4"
			(at 0.78 -0.38 180)
			(layer "B.SilkS")
			(effects
				(font
					(size 0.7 0.7)
					(thickness 0.15)
				)
				(justify left bottom mirror)
			)
		)
		(property "Value" "C_100n_0201"
			(at 0 -1.4 180)
			(layer "B.Fab")
			(hide yes)
			(effects
				(font
					(size 0.7 0.7)
					(thickness 0.15)
				)
				(justify left bottom mirror)
			)
		)
		(property "Description" "SMD Multilayer Ceramic Capacitor, 0.1 µF, 6.3 V, 0201 [0603 Metric], ± 10%, X6S, CC Series"
			(at 0 0 0)
			(layer "F.Fab")
			(hide yes)
			(effects
				(font
					(size 1.27 1.27)
					(thickness 0.15)
				)
			)
		)
		(property "Author" "Antmicro"
			(at 0 0 0)
			(layer "B.Fab")
			(hide yes)
			(effects
				(font
					(size 1 1)
					(thickness 0.15)
				)
				(justify mirror)
			)
		)
		(property "Dielectric" ""
			(at 0 0 0)
			(layer "B.Fab")
			(hide yes)
			(effects
				(font
					(size 1 1)
					(thickness 0.15)
				)
				(justify mirror)
			)
		)
		(property "License" "Apache-2.0"
			(at 0 0 0)
			(layer "B.Fab")
			(hide yes)
			(effects
				(font
					(size 1 1)
					(thickness 0.15)
				)
				(justify mirror)
			)
		)
		(property "MPN" "CC0201KRX6S5BB104"
			(at 0 0 0)
			(layer "B.Fab")
			(hide yes)
			(effects
				(font
					(size 1 1)
					(thickness 0.15)
				)
				(justify mirror)
			)
		)
		(property "Manufacturer" "YAGEO"
			(at 0 0 0)
			(layer "B.Fab")
			(hide yes)
			(effects
				(font
					(size 1 1)
					(thickness 0.15)
				)
				(justify mirror)
			)
		)
		(property "Public" "False"
			(at 0 0 0)
			(layer "B.Fab")
			(hide yes)
			(effects
				(font
					(size 1 1)
					(thickness 0.15)
				)
				(justify mirror)
			)
		)
		(property "Val" "100n"
			(at 0 0 0)
			(layer "B.Fab")
			(hide yes)
			(effects
				(font
					(size 1 1)
					(thickness 0.15)
				)
				(justify mirror)
			)
		)
		(property "Voltage" ""
			(at 0 0 0)
			(layer "B.Fab")
			(hide yes)
			(effects
				(font
					(size 1 1)
					(thickness 0.15)
				)
				(justify mirror)
			)
		)
		(sheetname "DDR5")
		(sheetfile "ddr5.kicad_sch")
		(attr smd)
		(fp_rect
			(start -0.7 0.35)
			(end 0.7 -0.35)
			(stroke
				(width 0.05)
				(type default)
			)
			(fill no)
			(layer "B.CrtYd")
		)
		(fp_rect
			(start 0.3 -0.15)
			(end -0.301 0.149)
			(stroke
				(width 0.15)
				(type solid)
			)
			(fill no)
			(layer "B.Fab")
		)
		(pad "" smd roundrect
			(at -0.349 0.002)
			(size 0.318 0.36)
			(layers "B.Paste")
			(roundrect_rratio 0.25)
		)
		(pad "" smd roundrect
			(at 0.341 0.002)
			(size 0.318 0.36)
			(layers "B.Paste")
			(roundrect_rratio 0.25)
		)
		(pad "1" smd roundrect
			(at -0.321 0.002)
			(size 0.46 0.4)
			(layers "B.Cu" "B.Mask")
			(roundrect_rratio 0.25)
			(net 2 "VDDQ")
			(pintype "passive")
		)
		(pad "2" smd roundrect
			(at 0.32 0.002)
			(size 0.46 0.4)
			(layers "B.Cu" "B.Mask")
			(roundrect_rratio 0.25)
			(net 1 "GND")
			(pintype "passive")
		)
	)
	(footprint "antmicro-footprints:C_0201"
		(layer "B.Cu")
		(at 145.3 82.1 -90)
		(descr "Capacitor SMD 0201")
		(tags "capacitor SMD 0201")
		(property "Reference" "C6"
			(at -0.9 0.52 90)
			(layer "B.SilkS")
			(effects
				(font
					(size 0.7 0.7)
					(thickness 0.15)
				)
				(justify left bottom mirror)
			)
		)
		(property "Value" "C_100n_0201"
			(at 0 -1.4 90)
			(layer "B.Fab")
			(hide yes)
			(effects
				(font
					(size 0.7 0.7)
					(thickness 0.15)
				)
				(justify left bottom mirror)
			)
		)
		(property "Description" "SMD Multilayer Ceramic Capacitor, 0.1 µF, 6.3 V, 0201 [0603 Metric], ± 10%, X6S, CC Series"
			(at 0 0 270)
			(layer "F.Fab")
			(hide yes)
			(effects
				(font
					(size 1.27 1.27)
					(thickness 0.15)
				)
			)
		)
		(property "Author" "Antmicro"
			(at 63.2 227.4 0)
			(layer "B.Fab")
			(hide yes)
			(effects
				(font
					(size 1 1)
					(thickness 0.15)
				)
				(justify mirror)
			)
		)
		(property "Dielectric" ""
			(at 63.2 227.4 0)
			(layer "B.Fab")
			(hide yes)
			(effects
				(font
					(size 1 1)
					(thickness 0.15)
				)
				(justify mirror)
			)
		)
		(property "License" "Apache-2.0"
			(at 63.2 227.4 0)
			(layer "B.Fab")
			(hide yes)
			(effects
				(font
					(size 1 1)
					(thickness 0.15)
				)
				(justify mirror)
			)
		)
		(property "MPN" "CC0201KRX6S5BB104"
			(at 63.2 227.4 0)
			(layer "B.Fab")
			(hide yes)
			(effects
				(font
					(size 1 1)
					(thickness 0.15)
				)
				(justify mirror)
			)
		)
		(property "Manufacturer" "YAGEO"
			(at 63.2 227.4 0)
			(layer "B.Fab")
			(hide yes)
			(effects
				(font
					(size 1 1)
					(thickness 0.15)
				)
				(justify mirror)
			)
		)
		(property "Public" "False"
			(at 63.2 227.4 0)
			(layer "B.Fab")
			(hide yes)
			(effects
				(font
					(size 1 1)
					(thickness 0.15)
				)
				(justify mirror)
			)
		)
		(property "Val" "100n"
			(at 63.2 227.4 0)
			(layer "B.Fab")
			(hide yes)
			(effects
				(font
					(size 1 1)
					(thickness 0.15)
				)
				(justify mirror)
			)
		)
		(property "Voltage" ""
			(at 63.2 227.4 0)
			(layer "B.Fab")
			(hide yes)
			(effects
				(font
					(size 1 1)
					(thickness 0.15)
				)
				(justify mirror)
			)
		)
		(sheetname "DDR5")
		(sheetfile "ddr5.kicad_sch")
		(attr smd)
		(fp_rect
			(start -0.7 0.35)
			(end 0.7 -0.35)
			(stroke
				(width 0.05)
				(type default)
			)
			(fill no)
			(layer "B.CrtYd")
		)
		(fp_rect
			(start 0.3 -0.15)
			(end -0.301 0.149)
			(stroke
				(width 0.15)
				(type solid)
			)
			(fill no)
			(layer "B.Fab")
		)
		(pad "" smd roundrect
			(at -0.349 0.002 270)
			(size 0.318 0.36)
			(layers "B.Paste")
			(roundrect_rratio 0.25)
		)
		(pad "" smd roundrect
			(at 0.341 0.002 270)
			(size 0.318 0.36)
			(layers "B.Paste")
			(roundrect_rratio 0.25)
		)
		(pad "1" smd roundrect
			(at -0.321 0.002 270)
			(size 0.46 0.4)
			(layers "B.Cu" "B.Mask")
			(roundrect_rratio 0.25)
			(net 18 "VDD")
			(pintype "passive")
		)
		(pad "2" smd roundrect
			(at 0.32 0.002 270)
			(size 0.46 0.4)
			(layers "B.Cu" "B.Mask")
			(roundrect_rratio 0.25)
			(net 1 "GND")
			(pintype "passive")
		)
	)
	(footprint "antmicro-footprints:C_0201"
		(layer "B.Cu")
		(at 149.15 88.05 180)
		(descr "Capacitor SMD 0201")
		(tags "capacitor SMD 0201")
		(property "Reference" "C8"
			(at -0.85 -2.04 0)
			(layer "B.SilkS")
			(effects
				(font
					(size 0.7 0.7)
					(thickness 0.15)
				)
				(justify left bottom mirror)
			)
		)
		(property "Value" "C_100n_0201"
			(at 0 -1.4 0)
			(layer "B.Fab")
			(hide yes)
			(effects
				(font
					(size 0.7 0.7)
					(thickness 0.15)
				)
				(justify left bottom mirror)
			)
		)
		(property "Description" "SMD Multilayer Ceramic Capacitor, 0.1 µF, 6.3 V, 0201 [0603 Metric], ± 10%, X6S, CC Series"
			(at 0 0 180)
			(layer "F.Fab")
			(hide yes)
			(effects
				(font
					(size 1.27 1.27)
					(thickness 0.15)
				)
			)
		)
		(property "Author" "Antmicro"
			(at 298.3 176.1 0)
			(layer "B.Fab")
			(hide yes)
			(effects
				(font
					(size 1 1)
					(thickness 0.15)
				)
				(justify mirror)
			)
		)
		(property "Dielectric" ""
			(at 298.3 176.1 0)
			(layer "B.Fab")
			(hide yes)
			(effects
				(font
					(size 1 1)
					(thickness 0.15)
				)
				(justify mirror)
			)
		)
		(property "License" "Apache-2.0"
			(at 298.3 176.1 0)
			(layer "B.Fab")
			(hide yes)
			(effects
				(font
					(size 1 1)
					(thickness 0.15)
				)
				(justify mirror)
			)
		)
		(property "MPN" "CC0201KRX6S5BB104"
			(at 298.3 176.1 0)
			(layer "B.Fab")
			(hide yes)
			(effects
				(font
					(size 1 1)
					(thickness 0.15)
				)
				(justify mirror)
			)
		)
		(property "Manufacturer" "YAGEO"
			(at 298.3 176.1 0)
			(layer "B.Fab")
			(hide yes)
			(effects
				(font
					(size 1 1)
					(thickness 0.15)
				)
				(justify mirror)
			)
		)
		(property "Public" "False"
			(at 298.3 176.1 0)
			(layer "B.Fab")
			(hide yes)
			(effects
				(font
					(size 1 1)
					(thickness 0.15)
				)
				(justify mirror)
			)
		)
		(property "Val" "100n"
			(at 298.3 176.1 0)
			(layer "B.Fab")
			(hide yes)
			(effects
				(font
					(size 1 1)
					(thickness 0.15)
				)
				(justify mirror)
			)
		)
		(property "Voltage" ""
			(at 298.3 176.1 0)
			(layer "B.Fab")
			(hide yes)
			(effects
				(font
					(size 1 1)
					(thickness 0.15)
				)
				(justify mirror)
			)
		)
		(sheetname "DDR5")
		(sheetfile "ddr5.kicad_sch")
		(attr smd)
		(fp_rect
			(start -0.7 0.35)
			(end 0.7 -0.35)
			(stroke
				(width 0.05)
				(type default)
			)
			(fill no)
			(layer "B.CrtYd")
		)
		(fp_rect
			(start 0.3 -0.15)
			(end -0.301 0.149)
			(stroke
				(width 0.15)
				(type solid)
			)
			(fill no)
			(layer "B.Fab")
		)
		(pad "" smd roundrect
			(at -0.349 0.002 180)
			(size 0.318 0.36)
			(layers "B.Paste")
			(roundrect_rratio 0.25)
		)
		(pad "" smd roundrect
			(at 0.341 0.002 180)
			(size 0.318 0.36)
			(layers "B.Paste")
			(roundrect_rratio 0.25)
		)
		(pad "1" smd roundrect
			(at -0.321 0.002 180)
			(size 0.46 0.4)
			(layers "B.Cu" "B.Mask")
			(roundrect_rratio 0.25)
			(net 2 "VDDQ")
			(pintype "passive")
		)
		(pad "2" smd roundrect
			(at 0.32 0.002 180)
			(size 0.46 0.4)
			(layers "B.Cu" "B.Mask")
			(roundrect_rratio 0.25)
			(net 1 "GND")
			(pintype "passive")
		)
	)
	(footprint "antmicro-footprints:C_0201"
		(layer "B.Cu")
		(at 148.82 80.55 90)
		(descr "Capacitor SMD 0201")
		(tags "capacitor SMD 0201")
		(property "Reference" "C9"
			(at 2.95 0.385 270)
			(layer "B.SilkS")
			(effects
				(font
					(size 0.7 0.7)
					(thickness 0.15)
				)
				(justify left bottom mirror)
			)
		)
		(property "Value" "C_100n_0201"
			(at 0 -1.4 270)
			(layer "B.Fab")
			(hide yes)
			(effects
				(font
					(size 0.7 0.7)
					(thickness 0.15)
				)
				(justify left bottom mirror)
			)
		)
		(property "Description" "SMD Multilayer Ceramic Capacitor, 0.1 µF, 6.3 V, 0201 [0603 Metric], ± 10%, X6S, CC Series"
			(at 0 0 90)
			(layer "F.Fab")
			(hide yes)
			(effects
				(font
					(size 1.27 1.27)
					(thickness 0.15)
				)
			)
		)
		(property "Author" "Antmicro"
			(at 229.37 -68.27 0)
			(layer "B.Fab")
			(hide yes)
			(effects
				(font
					(size 1 1)
					(thickness 0.15)
				)
				(justify mirror)
			)
		)
		(property "Dielectric" ""
			(at 229.37 -68.27 0)
			(layer "B.Fab")
			(hide yes)
			(effects
				(font
					(size 1 1)
					(thickness 0.15)
				)
				(justify mirror)
			)
		)
		(property "License" "Apache-2.0"
			(at 229.37 -68.27 0)
			(layer "B.Fab")
			(hide yes)
			(effects
				(font
					(size 1 1)
					(thickness 0.15)
				)
				(justify mirror)
			)
		)
		(property "MPN" "CC0201KRX6S5BB104"
			(at 229.37 -68.27 0)
			(layer "B.Fab")
			(hide yes)
			(effects
				(font
					(size 1 1)
					(thickness 0.15)
				)
				(justify mirror)
			)
		)
		(property "Manufacturer" "YAGEO"
			(at 229.37 -68.27 0)
			(layer "B.Fab")
			(hide yes)
			(effects
				(font
					(size 1 1)
					(thickness 0.15)
				)
				(justify mirror)
			)
		)
		(property "Public" "False"
			(at 229.37 -68.27 0)
			(layer "B.Fab")
			(hide yes)
			(effects
				(font
					(size 1 1)
					(thickness 0.15)
				)
				(justify mirror)
			)
		)
		(property "Val" "100n"
			(at 229.37 -68.27 0)
			(layer "B.Fab")
			(hide yes)
			(effects
				(font
					(size 1 1)
					(thickness 0.15)
				)
				(justify mirror)
			)
		)
		(property "Voltage" ""
			(at 229.37 -68.27 0)
			(layer "B.Fab")
			(hide yes)
			(effects
				(font
					(size 1 1)
					(thickness 0.15)
				)
				(justify mirror)
			)
		)
		(sheetname "DDR5")
		(sheetfile "ddr5.kicad_sch")
		(attr smd)
		(fp_rect
			(start -0.7 0.35)
			(end 0.7 -0.35)
			(stroke
				(width 0.05)
				(type default)
			)
			(fill no)
			(layer "B.CrtYd")
		)
		(fp_rect
			(start 0.3 -0.15)
			(end -0.301 0.149)
			(stroke
				(width 0.15)
				(type solid)
			)
			(fill no)
			(layer "B.Fab")
		)
		(pad "" smd roundrect
			(at -0.349 0.002 90)
			(size 0.318 0.36)
			(layers "B.Paste")
			(roundrect_rratio 0.25)
		)
		(pad "" smd roundrect
			(at 0.341 0.002 90)
			(size 0.318 0.36)
			(layers "B.Paste")
			(roundrect_rratio 0.25)
		)
		(pad "1" smd roundrect
			(at -0.321 0.002 90)
			(size 0.46 0.4)
			(layers "B.Cu" "B.Mask")
			(roundrect_rratio 0.25)
			(net 18 "VDD")
			(pintype "passive")
		)
		(pad "2" smd roundrect
			(at 0.32 0.002 90)
			(size 0.46 0.4)
			(layers "B.Cu" "B.Mask")
			(roundrect_rratio 0.25)
			(net 1 "GND")
			(pintype "passive")
		)
	)
	(footprint "antmicro-footprints:C_0201"
		(layer "B.Cu")
		(at 145.3 83.6 90)
		(descr "Capacitor SMD 0201")
		(tags "capacitor SMD 0201")
		(property "Reference" "C26"
			(at 0.97 -0.53 270)
			(layer "B.SilkS")
			(effects
				(font
					(size 0.7 0.7)
					(thickness 0.15)
				)
				(justify left bottom mirror)
			)
		)
		(property "Value" "C_100n_0201"
			(at 0 -1.4 270)
			(layer "B.Fab")
			(hide yes)
			(effects
				(font
					(size 0.7 0.7)
					(thickness 0.15)
				)
				(justify left bottom mirror)
			)
		)
		(property "Description" "SMD Multilayer Ceramic Capacitor, 0.1 µF, 6.3 V, 0201 [0603 Metric], ± 10%, X6S, CC Series"
			(at 0 0 90)
			(layer "F.Fab")
			(hide yes)
			(effects
				(font
					(size 1.27 1.27)
					(thickness 0.15)
				)
			)
		)
		(property "Author" "Antmicro"
			(at 228.9 -61.7 0)
			(layer "B.Fab")
			(hide yes)
			(effects
				(font
					(size 1 1)
					(thickness 0.15)
				)
				(justify mirror)
			)
		)
		(property "Dielectric" ""
			(at 228.9 -61.7 0)
			(layer "B.Fab")
			(hide yes)
			(effects
				(font
					(size 1 1)
					(thickness 0.15)
				)
				(justify mirror)
			)
		)
		(property "License" "Apache-2.0"
			(at 228.9 -61.7 0)
			(layer "B.Fab")
			(hide yes)
			(effects
				(font
					(size 1 1)
					(thickness 0.15)
				)
				(justify mirror)
			)
		)
		(property "MPN" "CC0201KRX6S5BB104"
			(at 228.9 -61.7 0)
			(layer "B.Fab")
			(hide yes)
			(effects
				(font
					(size 1 1)
					(thickness 0.15)
				)
				(justify mirror)
			)
		)
		(property "Manufacturer" "YAGEO"
			(at 228.9 -61.7 0)
			(layer "B.Fab")
			(hide yes)
			(effects
				(font
					(size 1 1)
					(thickness 0.15)
				)
				(justify mirror)
			)
		)
		(property "Public" "False"
			(at 228.9 -61.7 0)
			(layer "B.Fab")
			(hide yes)
			(effects
				(font
					(size 1 1)
					(thickness 0.15)
				)
				(justify mirror)
			)
		)
		(property "Val" "100n"
			(at 228.9 -61.7 0)
			(layer "B.Fab")
			(hide yes)
			(effects
				(font
					(size 1 1)
					(thickness 0.15)
				)
				(justify mirror)
			)
		)
		(property "Voltage" ""
			(at 228.9 -61.7 0)
			(layer "B.Fab")
			(hide yes)
			(effects
				(font
					(size 1 1)
					(thickness 0.15)
				)
				(justify mirror)
			)
		)
		(sheetname "DDR5")
		(sheetfile "ddr5.kicad_sch")
		(attr smd)
		(fp_rect
			(start -0.7 0.35)
			(end 0.7 -0.35)
			(stroke
				(width 0.05)
				(type default)
			)
			(fill no)
			(layer "B.CrtYd")
		)
		(fp_rect
			(start 0.3 -0.15)
			(end -0.301 0.149)
			(stroke
				(width 0.15)
				(type solid)
			)
			(fill no)
			(layer "B.Fab")
		)
		(pad "" smd roundrect
			(at -0.349 0.002 90)
			(size 0.318 0.36)
			(layers "B.Paste")
			(roundrect_rratio 0.25)
		)
		(pad "" smd roundrect
			(at 0.341 0.002 90)
			(size 0.318 0.36)
			(layers "B.Paste")
			(roundrect_rratio 0.25)
		)
		(pad "1" smd roundrect
			(at -0.321 0.002 90)
			(size 0.46 0.4)
			(layers "B.Cu" "B.Mask")
			(roundrect_rratio 0.25)
			(net 18 "VDD")
			(pintype "passive")
		)
		(pad "2" smd roundrect
			(at 0.32 0.002 90)
			(size 0.46 0.4)
			(layers "B.Cu" "B.Mask")
			(roundrect_rratio 0.25)
			(net 1 "GND")
			(pintype "passive")
		)
	)
)
